FILE_TYPE = MACRO_DRAWING;
SET COLOR_WIRE YELLOW;
SET COLOR_PROP ORANGE;
SET COLOR_DOT WHITE;
SET COLOR_ARC YELLOW;
SET COLOR_BODY GREEN;
SET COLOR_NOTE PURPLE;
SET PROP_DISPLAY VALUE;
SET PAGE_NUMBER P525;
FORCEADD FERRITEBEAD..1
(-300 3400);
FORCEPROP 0 LAST PACKAGE 0603
J 0
(-300 3450);
DISPLAY 1.021277 (-300 3450);
FORCEPROP 1 LAST VALUE 26OHM
J 0
(0 3450);
DISPLAY 1.212766 (0 3450);
PAINT GREEN (0 3450);
FORCEPROP 1 LAST TOLERANCE 25%
J 0
(-400 3450);
DISPLAY 1.212766 (-400 3450);
PAINT GREEN (-400 3450);
DISPLAY INVISIBLE (-400 3450);
FORCEPROP 1 LAST CLS_PN G191-10101-01
J 2
(-350 3450);
DISPLAY 1.212766 (-350 3450);
PAINT GREEN (-350 3450);
DISPLAY INVISIBLE (-350 3450);
FORCEPROP 1 LAST CDS_LMAN_SYM_OUTLINE 0,0,200,-100
J 0
(-300 3400);
DISPLAY 0.468085 (-300 3400);
PAINT GREEN (-300 3400);
DISPLAY INVISIBLE (-300 3400);
FORCEPROP 1 LAST PATH I10
J 2
(-350 3450);
DISPLAY 1.212766 (-350 3450);
PAINT GREEN (-350 3450);
DISPLAY INVISIBLE (-350 3450);
FORCEPROP 2 LAST CDS_LIB passive
J 0
(-300 3400);
DISPLAY INVISIBLE (-300 3400);
FORCEPROP 1 LAST $LOCATION L23
J 2
(-360 3459);
DISPLAY 1.212766 (-360 3459);
PAINT GREEN (-360 3459);
FORCEPROP 0 LASTPIN (-400 3350) $PN 1
J 2
(-410 3360);
DISPLAY 0.680851 (-410 3360);
PAINT MONO (-410 3360);
FORCEPROP 0 LASTPIN (0 3350) $PN 2
J 0
(10 3360);
DISPLAY 0.680851 (10 3360);
PAINT MONO (10 3360);
FORCEPROP 0 LAST CDS_LOCATION L23
J 0
(0 3550);
DISPLAY 1.021277 (0 3550);
DISPLAY INVISIBLE (0 3550);
FORCEPROP 0 LAST $SEC 1
J 0
(0 3550);
DISPLAY 0.680851 (0 3550);
PAINT MONO (0 3550);
DISPLAY INVISIBLE (0 3550);
FORCEPROP 0 LAST CDS_SEC 1
J 0
(0 3550);
DISPLAY 1.021277 (0 3550);
DISPLAY INVISIBLE (0 3550);
FORCEADD DIODE_2F..1
(-1600 3350);
FORCEPROP 1 LAST CLS_PN G122-10186-01
J 0
(-2000 3450);
DISPLAY 1.212766 (-2000 3450);
PAINT GREEN (-2000 3450);
FORCEPROP 1 LAST CDS_LMAN_SYM_OUTLINE -50,100,50,-100
J 0
(-1600 3350);
DISPLAY 0.468085 (-1600 3350);
PAINT GREEN (-1600 3350);
DISPLAY INVISIBLE (-1600 3350);
FORCEPROP 2 LAST CDS_LIB discrete
J 0
(-1600 3350);
DISPLAY INVISIBLE (-1600 3350);
FORCEPROP 1 LAST PATH I102
J 0
(-1500 3550);
DISPLAY 1.212766 (-1500 3550);
PAINT GREEN (-1500 3550);
DISPLAY INVISIBLE (-1500 3550);
FORCEPROP 1 LAST $LOCATION CR1
J 2
(-1950 3350);
DISPLAY 1.212766 (-1950 3350);
PAINT GREEN (-1950 3350);
FORCEPROP 0 LASTPIN (-1850 3350) $PN A
J 2
(-1860 3360);
DISPLAY 0.680851 (-1860 3360);
PAINT MONO (-1860 3360);
FORCEPROP 0 LASTPIN (-1350 3350) $PN C
J 0
(-1340 3360);
DISPLAY 0.680851 (-1340 3360);
PAINT MONO (-1340 3360);
FORCEPROP 0 LAST CDS_LOCATION CR1
J 0
(-2000 3550);
DISPLAY 1.021277 (-2000 3550);
DISPLAY INVISIBLE (-2000 3550);
FORCEPROP 0 LAST $SEC 1
J 0
(-2000 3550);
DISPLAY 0.680851 (-2000 3550);
PAINT MONO (-2000 3550);
DISPLAY INVISIBLE (-2000 3550);
FORCEPROP 0 LAST CDS_SEC 1
J 0
(-2000 3550);
DISPLAY 1.021277 (-2000 3550);
DISPLAY INVISIBLE (-2000 3550);
FORCEADD DIODE_2F..1
(-1600 3200);
FORCEPROP 0 LAST NO_ASSY TRUE
J 0
(-2000 2900);
DISPLAY 1.021277 (-2000 2900);
DISPLAY BOTH (-2000 2900);
FORCEPROP 1 LAST CLS_PN G122-10186-01
J 0
(-2000 3050);
DISPLAY 1.212766 (-2000 3050);
PAINT GREEN (-2000 3050);
FORCEPROP 1 LAST PATH I104
J 0
(-1500 3400);
DISPLAY 1.212766 (-1500 3400);
PAINT GREEN (-1500 3400);
DISPLAY INVISIBLE (-1500 3400);
FORCEPROP 1 LAST CDS_LMAN_SYM_OUTLINE -50,100,50,-100
J 0
(-1600 3200);
DISPLAY 0.468085 (-1600 3200);
PAINT GREEN (-1600 3200);
DISPLAY INVISIBLE (-1600 3200);
FORCEPROP 2 LAST CDS_LIB discrete
J 0
(-1600 3200);
DISPLAY INVISIBLE (-1600 3200);
FORCEPROP 1 LAST $LOCATION CR2
J 2
(-1950 3200);
DISPLAY 1.212766 (-1950 3200);
PAINT GREEN (-1950 3200);
FORCEPROP 0 LASTPIN (-1850 3200) $PN A
J 2
(-1860 3210);
DISPLAY 0.680851 (-1860 3210);
PAINT MONO (-1860 3210);
FORCEPROP 0 LASTPIN (-1350 3200) $PN C
J 0
(-1340 3210);
DISPLAY 0.680851 (-1340 3210);
PAINT MONO (-1340 3210);
FORCEPROP 0 LAST CDS_LOCATION CR2
J 0
(-1950 3300);
DISPLAY 1.021277 (-1950 3300);
DISPLAY INVISIBLE (-1950 3300);
FORCEPROP 0 LAST $SEC 1
J 0
(-1950 3300);
DISPLAY 0.680851 (-1950 3300);
PAINT MONO (-1950 3300);
DISPLAY INVISIBLE (-1950 3300);
FORCEPROP 0 LAST CDS_SEC 1
J 0
(-1950 3300);
DISPLAY 1.021277 (-1950 3300);
DISPLAY INVISIBLE (-1950 3300);
FORCEADD VCC..1
(-2350 3650);
FORCEPROP 3 LASTPIN (-2300 3600) SIG_NAME XP5R0V\g
J 0
(-2290 3610);
DISPLAY 0.659574 (-2290 3610);
PAINT MONO (-2290 3610);
DISPLAY INVISIBLE (-2290 3610);
FORCEPROP 1 LAST HDL_POWER XP5R0V
J 1
(-2295 3705);
DISPLAY 1.021277 (-2295 3705);
PAINT GREEN (-2295 3705);
FORCEPROP 0 LAST VOLTAGE 5.0
J 0
(-2500 3800);
DISPLAY 1.021277 (-2500 3800);
DISPLAY BOTH (-2500 3800);
FORCEPROP 1 LAST CDS_LMAN_SYM_OUTLINE -250,250,250,-250
J 0
(-2350 3650);
DISPLAY 0.468085 (-2350 3650);
PAINT GREEN (-2350 3650);
DISPLAY INVISIBLE (-2350 3650);
FORCEPROP 2 LAST CDS_LIB cls
J 0
(-2350 3650);
DISPLAY INVISIBLE (-2350 3650);
FORCEPROP 1 LAST BODY_TYPE PLUMBING
J 0
(-2395 3607);
DISPLAY 0.340426 (-2395 3607);
PAINT GREEN (-2395 3607);
DISPLAY INVISIBLE (-2395 3607);
FORCEPROP 1 LAST PATH I105
J 0
(-2315 3740);
DISPLAY 0.808511 (-2315 3740);
PAINT GREEN (-2315 3740);
DISPLAY INVISIBLE (-2315 3740);
FORCEADD VCC..1
(5150 3950);
FORCEPROP 3 LASTPIN (5200 3900) SIG_NAME XP3R3V_FPGA\g
J 0
(5210 3910);
DISPLAY 0.659574 (5210 3910);
PAINT MONO (5210 3910);
DISPLAY INVISIBLE (5210 3910);
FORCEPROP 0 LAST VOLTAGE 3.3V
J 0
(4950 4050);
DISPLAY 1.021277 (4950 4050);
DISPLAY BOTH (4950 4050);
FORCEPROP 1 LAST HDL_POWER XP3R3V_FPGA
J 1
(5205 4005);
DISPLAY 1.021277 (5205 4005);
PAINT GREEN (5205 4005);
FORCEPROP 1 LAST BODY_TYPE PLUMBING
J 0
(5105 3907);
DISPLAY 0.340426 (5105 3907);
PAINT GREEN (5105 3907);
DISPLAY INVISIBLE (5105 3907);
FORCEPROP 1 LAST CDS_LMAN_SYM_OUTLINE -250,250,250,-250
J 0
(5150 3950);
DISPLAY 0.468085 (5150 3950);
PAINT GREEN (5150 3950);
DISPLAY INVISIBLE (5150 3950);
FORCEPROP 1 LAST PATH I107
J 0
(5185 4040);
DISPLAY 0.808511 (5185 4040);
PAINT GREEN (5185 4040);
DISPLAY INVISIBLE (5185 4040);
FORCEPROP 2 LAST CDS_LIB cls
J 0
(5150 3950);
DISPLAY INVISIBLE (5150 3950);
FORCEADD FERRITEBEAD..1
(5700 3750);
FORCEPROP 0 LAST NO_ASSY TRUE
J 0
(5600 3600);
DISPLAY 1.021277 (5600 3600);
DISPLAY BOTH (5600 3600);
FORCEPROP 0 LAST PACKAGE 0603
J 0
(5700 3800);
DISPLAY 1.021277 (5700 3800);
FORCEPROP 1 LAST VALUE 120OHM
J 0
(5950 3800);
DISPLAY 1.212766 (5950 3800);
PAINT GREEN (5950 3800);
FORCEPROP 2 LAST CDS_LIB passive
J 0
(5700 3750);
DISPLAY INVISIBLE (5700 3750);
FORCEPROP 1 LAST PATH I108
J 2
(5650 3800);
DISPLAY 1.212766 (5650 3800);
PAINT GREEN (5650 3800);
DISPLAY INVISIBLE (5650 3800);
FORCEPROP 1 LAST CDS_LMAN_SYM_OUTLINE 0,0,200,-100
J 0
(5700 3750);
DISPLAY 0.468085 (5700 3750);
PAINT GREEN (5700 3750);
DISPLAY INVISIBLE (5700 3750);
FORCEPROP 1 LAST TOLERANCE 25%
J 0
(5600 3800);
DISPLAY 1.212766 (5600 3800);
PAINT GREEN (5600 3800);
DISPLAY INVISIBLE (5600 3800);
FORCEPROP 1 LAST CLS_PN G191-10100-01
J 2
(5650 3800);
DISPLAY 1.212766 (5650 3800);
PAINT GREEN (5650 3800);
DISPLAY INVISIBLE (5650 3800);
FORCEPROP 1 LAST $LOCATION L24
J 2
(5640 3809);
DISPLAY 1.212766 (5640 3809);
PAINT GREEN (5640 3809);
FORCEPROP 0 LASTPIN (5600 3700) $PN 1
J 2
(5590 3710);
DISPLAY 0.680851 (5590 3710);
PAINT MONO (5590 3710);
FORCEPROP 0 LASTPIN (6000 3700) $PN 2
J 0
(6010 3710);
DISPLAY 0.680851 (6010 3710);
PAINT MONO (6010 3710);
FORCEPROP 0 LAST CDS_LOCATION L24
J 0
(5950 3900);
DISPLAY 1.021277 (5950 3900);
DISPLAY INVISIBLE (5950 3900);
FORCEPROP 0 LAST $SEC 1
J 0
(5950 3900);
DISPLAY 0.680851 (5950 3900);
PAINT MONO (5950 3900);
DISPLAY INVISIBLE (5950 3900);
FORCEPROP 0 LAST CDS_SEC 1
J 0
(5950 3900);
DISPLAY 1.021277 (5950 3900);
DISPLAY INVISIBLE (5950 3900);
FORCEADD GND_SG..1
(250 1300);
FORCEPROP 3 LASTPIN (300 1350) SIG_NAME SG\g
J 0
(310 1360);
DISPLAY 0.659574 (310 1360);
PAINT MONO (310 1360);
DISPLAY INVISIBLE (310 1360);
FORCEPROP 1 LAST HDL_POWER SG
J 1
(305 1205);
DISPLAY 0.808511 (305 1205);
PAINT GREEN (305 1205);
FORCEPROP 1 LAST CDS_LMAN_SYM_OUTLINE 0,0,100,-50
J 0
(250 1300);
DISPLAY 0.468085 (250 1300);
PAINT GREEN (250 1300);
DISPLAY INVISIBLE (250 1300);
FORCEPROP 2 LAST CDS_LIB cls
J 0
(250 1300);
DISPLAY INVISIBLE (250 1300);
FORCEPROP 1 LAST PATH I11
J 0
(285 1300);
DISPLAY 0.808511 (285 1300);
PAINT GREEN (285 1300);
DISPLAY INVISIBLE (285 1300);
FORCEPROP 1 LAST BODY_TYPE PLUMBING
J 0
(265 1285);
DISPLAY 0.808511 (265 1285);
PAINT GREEN (265 1285);
DISPLAY INVISIBLE (265 1285);
FORCEADD RESISTOR..2
(300 1950);
FORCEPROP 1 LAST VALUE 10KOHM
J 0
(350 2000);
DISPLAY 1.212766 (350 2000);
PAINT GREEN (350 2000);
FORCEPROP 0 LAST PACKAGE 0402
J 0
(350 1750);
DISPLAY 1.021277 (350 1750);
FORCEPROP 1 LAST CDS_LMAN_SYM_OUTLINE -50,50,50,-100
J 0
(300 1950);
DISPLAY 0.468085 (300 1950);
PAINT GREEN (300 1950);
DISPLAY INVISIBLE (300 1950);
FORCEPROP 2 LAST CDS_LIB passive
J 0
(300 1950);
DISPLAY INVISIBLE (300 1950);
FORCEPROP 1 LAST PATH I13
J 0
(103 2055);
DISPLAY 1.212766 (103 2055);
PAINT GREEN (103 2055);
DISPLAY INVISIBLE (103 2055);
FORCEPROP 1 LAST TOLERANCE 1%
J 0
(103 2205);
DISPLAY 1.212766 (103 2205);
PAINT GREEN (103 2205);
DISPLAY INVISIBLE (103 2205);
FORCEPROP 1 LAST CLS_PN G155-11002-01
J 0
(164 2150);
DISPLAY 1.212766 (164 2150);
PAINT GREEN (164 2150);
DISPLAY INVISIBLE (164 2150);
FORCEPROP 1 LAST $LOCATION R488
J 0
(350 1800);
DISPLAY 1.212766 (350 1800);
PAINT GREEN (350 1800);
FORCEPROP 0 LASTPIN (300 2050) $PN 1
R 1
J 0
(290 2060);
DISPLAY 0.680851 (290 2060);
PAINT MONO (290 2060);
FORCEPROP 0 LASTPIN (300 1800) $PN 2
R 1
J 2
(290 1790);
DISPLAY 0.680851 (290 1790);
PAINT MONO (290 1790);
FORCEPROP 0 LAST CDS_LOCATION R488
J 0
(350 2100);
DISPLAY 1.021277 (350 2100);
DISPLAY INVISIBLE (350 2100);
FORCEPROP 0 LAST $SEC 1
J 0
(350 2100);
DISPLAY 0.680851 (350 2100);
PAINT MONO (350 2100);
DISPLAY INVISIBLE (350 2100);
FORCEPROP 0 LAST CDS_SEC 1
J 0
(350 2100);
DISPLAY 1.021277 (350 2100);
DISPLAY INVISIBLE (350 2100);
FORCEADD CAPACITOR..2
(850 1950);
FORCEPROP 0 LAST PACKAGE 0402
J 0
(950 1900);
DISPLAY 1.021277 (950 1900);
FORCEPROP 0 LAST VOLTAGE 25V
J 0
(950 2100);
DISPLAY 1.021277 (950 2100);
FORCEPROP 1 LAST VALUE 0.1UF
J 0
(950 2000);
DISPLAY 1.212766 (950 2000);
PAINT GREEN (950 2000);
FORCEPROP 1 LAST TOLERANCE 10%
J 0
(700 2050);
DISPLAY 1.212766 (700 2050);
PAINT GREEN (700 2050);
DISPLAY INVISIBLE (700 2050);
FORCEPROP 1 LAST CLS_PN G105-0B104-EK
J 0
(750 2000);
DISPLAY 1.212766 (750 2000);
PAINT GREEN (750 2000);
DISPLAY INVISIBLE (750 2000);
FORCEPROP 1 LAST CDS_LMAN_SYM_OUTLINE -50,0,50,-50
J 0
(850 1950);
DISPLAY 0.468085 (850 1950);
PAINT GREEN (850 1950);
DISPLAY INVISIBLE (850 1950);
FORCEPROP 1 LAST PATH I14
J 0
(750 2000);
DISPLAY 1.212766 (750 2000);
PAINT GREEN (750 2000);
DISPLAY INVISIBLE (750 2000);
FORCEPROP 2 LAST CDS_LIB passive
J 0
(850 1950);
DISPLAY INVISIBLE (850 1950);
FORCEPROP 2 LASTPIN (850 2050) SIG_NAME UN$525$CAPACITOR$I14$1
J 0
(860 2060);
DISPLAY 0.659574 (860 2060);
PAINT MONO (860 2060);
DISPLAY INVISIBLE (860 2060);
FORCEPROP 1 LAST $LOCATION C302
J 0
(900 1800);
DISPLAY 1.212766 (900 1800);
PAINT GREEN (900 1800);
FORCEPROP 0 LASTPIN (850 2050) $PN 1
R 1
J 0
(840 2060);
DISPLAY 0.680851 (840 2060);
PAINT MONO (840 2060);
FORCEPROP 0 LASTPIN (850 1800) $PN 2
R 1
J 2
(840 1790);
DISPLAY 0.680851 (840 1790);
PAINT MONO (840 1790);
FORCEPROP 0 LAST CDS_LOCATION C302
J 0
(950 2150);
DISPLAY 1.021277 (950 2150);
DISPLAY INVISIBLE (950 2150);
FORCEPROP 0 LAST $SEC 1
J 0
(950 2150);
DISPLAY 0.680851 (950 2150);
PAINT MONO (950 2150);
DISPLAY INVISIBLE (950 2150);
FORCEPROP 0 LAST CDS_SEC 1
J 0
(950 2150);
DISPLAY 1.021277 (950 2150);
DISPLAY INVISIBLE (950 2150);
FORCEADD CAPACITOR..2
(800 3050);
FORCEPROP 0 LAST VOLTAGE 25V
J 0
(900 3175);
DISPLAY 1.021277 (900 3175);
FORCEPROP 1 LAST VALUE 10UF
J 0
(900 2950);
DISPLAY 1.212766 (900 2950);
PAINT GREEN (900 2950);
FORCEPROP 0 LAST PACKAGE 0805
J 0
(900 3075);
DISPLAY 1.021277 (900 3075);
FORCEPROP 2 LAST CDS_LIB passive
J 0
(800 3050);
DISPLAY INVISIBLE (800 3050);
FORCEPROP 1 LAST PATH I16
J 0
(700 3100);
DISPLAY 1.212766 (700 3100);
PAINT GREEN (700 3100);
DISPLAY INVISIBLE (700 3100);
FORCEPROP 1 LAST CDS_LMAN_SYM_OUTLINE -50,0,50,-50
J 0
(800 3050);
DISPLAY 0.468085 (800 3050);
PAINT GREEN (800 3050);
DISPLAY INVISIBLE (800 3050);
FORCEPROP 1 LAST CLS_PN G107-0F106-EM
J 0
(700 3100);
DISPLAY 1.212766 (700 3100);
PAINT GREEN (700 3100);
DISPLAY INVISIBLE (700 3100);
FORCEPROP 1 LAST TOLERANCE 20%
J 0
(650 3150);
DISPLAY 1.212766 (650 3150);
PAINT GREEN (650 3150);
DISPLAY INVISIBLE (650 3150);
FORCEPROP 2 LASTPIN (800 3150) SIG_NAME UN$525$CAPACITOR$I16$1
J 0
(810 3160);
DISPLAY 0.659574 (810 3160);
PAINT MONO (810 3160);
DISPLAY INVISIBLE (810 3160);
FORCEPROP 1 LAST $LOCATION C300
J 0
(850 2900);
DISPLAY 1.212766 (850 2900);
PAINT GREEN (850 2900);
FORCEPROP 0 LASTPIN (800 3150) $PN 1
R 1
J 0
(790 3160);
DISPLAY 0.680851 (790 3160);
PAINT MONO (790 3160);
FORCEPROP 0 LASTPIN (800 2900) $PN 2
R 1
J 2
(790 2890);
DISPLAY 0.680851 (790 2890);
PAINT MONO (790 2890);
FORCEPROP 0 LAST CDS_LOCATION C300
J 0
(900 3250);
DISPLAY 1.021277 (900 3250);
DISPLAY INVISIBLE (900 3250);
FORCEPROP 0 LAST $SEC 1
J 0
(900 3250);
DISPLAY 0.680851 (900 3250);
PAINT MONO (900 3250);
DISPLAY INVISIBLE (900 3250);
FORCEPROP 0 LAST CDS_SEC 1
J 0
(900 3250);
DISPLAY 1.021277 (900 3250);
DISPLAY INVISIBLE (900 3250);
FORCEADD GND_SG..1
(1300 1450);
FORCEPROP 3 LASTPIN (1350 1500) SIG_NAME SG\g
J 0
(1360 1510);
DISPLAY 0.659574 (1360 1510);
PAINT MONO (1360 1510);
DISPLAY INVISIBLE (1360 1510);
FORCEPROP 2 LAST VOLTAGE 0
J 0
(1400 1400);
DISPLAY 1.021277 (1400 1400);
FORCEPROP 1 LAST HDL_POWER SG
J 1
(1355 1355);
DISPLAY 0.808511 (1355 1355);
PAINT GREEN (1355 1355);
FORCEPROP 2 LAST CDS_LIB cls
J 0
(1300 1450);
DISPLAY INVISIBLE (1300 1450);
FORCEPROP 1 LAST PATH I17
J 0
(1335 1450);
DISPLAY 0.808511 (1335 1450);
PAINT GREEN (1335 1450);
DISPLAY INVISIBLE (1335 1450);
FORCEPROP 1 LAST CDS_LMAN_SYM_OUTLINE 0,0,100,-50
J 0
(1300 1450);
DISPLAY 0.468085 (1300 1450);
PAINT GREEN (1300 1450);
DISPLAY INVISIBLE (1300 1450);
FORCEPROP 1 LAST BODY_TYPE PLUMBING
J 0
(1315 1435);
DISPLAY 0.808511 (1315 1435);
PAINT GREEN (1315 1435);
DISPLAY INVISIBLE (1315 1435);
FORCEADD CAPACITOR..2
(1350 1850);
FORCEPROP 1 LAST VALUE 0.01UF
J 0
(1450 1750);
DISPLAY 0.978723 (1450 1750);
PAINT GREEN (1450 1750);
FORCEPROP 0 LAST VOLTAGE 25V
J 0
(1450 1950);
DISPLAY 1.021277 (1450 1950);
FORCEPROP 0 LAST PACKAGE 0201
J 0
(1450 1850);
DISPLAY 1.021277 (1450 1850);
FORCEPROP 2 LAST CDS_LIB passive
J 0
(1350 1850);
DISPLAY INVISIBLE (1350 1850);
FORCEPROP 1 LAST PATH I18
J 0
(1250 1900);
DISPLAY 1.212766 (1250 1900);
PAINT GREEN (1250 1900);
DISPLAY INVISIBLE (1250 1900);
FORCEPROP 1 LAST CDS_LMAN_SYM_OUTLINE -50,0,50,-50
J 0
(1350 1850);
DISPLAY 0.468085 (1350 1850);
PAINT GREEN (1350 1850);
DISPLAY INVISIBLE (1350 1850);
FORCEPROP 1 LAST CLS_PN G104-0B103-EK
J 0
(1250 1900);
DISPLAY 1.212766 (1250 1900);
PAINT GREEN (1250 1900);
DISPLAY INVISIBLE (1250 1900);
FORCEPROP 1 LAST TOLERANCE 10%
J 0
(1200 1950);
DISPLAY 1.212766 (1200 1950);
PAINT GREEN (1200 1950);
DISPLAY INVISIBLE (1200 1950);
FORCEPROP 2 LASTPIN (1350 1950) SIG_NAME UN$525$CAPACITOR$I18$1
J 0
(1360 1960);
DISPLAY 0.659574 (1360 1960);
PAINT MONO (1360 1960);
DISPLAY INVISIBLE (1360 1960);
FORCEPROP 1 LAST $LOCATION C307
J 0
(1400 1700);
DISPLAY 1.212766 (1400 1700);
PAINT GREEN (1400 1700);
FORCEPROP 0 LASTPIN (1350 1950) $PN 1
R 1
J 0
(1340 1960);
DISPLAY 0.680851 (1340 1960);
PAINT MONO (1340 1960);
FORCEPROP 0 LASTPIN (1350 1700) $PN 2
R 1
J 2
(1340 1690);
DISPLAY 0.680851 (1340 1690);
PAINT MONO (1340 1690);
FORCEPROP 0 LAST CDS_LOCATION C307
J 0
(1450 2000);
DISPLAY 1.021277 (1450 2000);
DISPLAY INVISIBLE (1450 2000);
FORCEPROP 0 LAST $SEC 1
J 0
(1450 2000);
DISPLAY 0.680851 (1450 2000);
PAINT MONO (1450 2000);
DISPLAY INVISIBLE (1450 2000);
FORCEPROP 0 LAST CDS_SEC 1
J 0
(1450 2000);
DISPLAY 1.021277 (1450 2000);
DISPLAY INVISIBLE (1450 2000);
FORCEADD GND_SG..1
(1200 2600);
FORCEPROP 3 LASTPIN (1250 2650) SIG_NAME SG\g
J 0
(1260 2660);
DISPLAY 0.659574 (1260 2660);
PAINT MONO (1260 2660);
DISPLAY INVISIBLE (1260 2660);
FORCEPROP 1 LAST HDL_POWER SG
J 1
(1255 2505);
DISPLAY 0.808511 (1255 2505);
PAINT GREEN (1255 2505);
FORCEPROP 2 LAST VOLTAGE 0
J 0
(1300 2550);
DISPLAY 1.021277 (1300 2550);
FORCEPROP 2 LAST CDS_LIB cls
J 0
(1200 2600);
DISPLAY INVISIBLE (1200 2600);
FORCEPROP 1 LAST PATH I19
J 0
(1235 2600);
DISPLAY 0.808511 (1235 2600);
PAINT GREEN (1235 2600);
DISPLAY INVISIBLE (1235 2600);
FORCEPROP 1 LAST CDS_LMAN_SYM_OUTLINE 0,0,100,-50
J 0
(1200 2600);
DISPLAY 0.468085 (1200 2600);
PAINT GREEN (1200 2600);
DISPLAY INVISIBLE (1200 2600);
FORCEPROP 1 LAST BODY_TYPE PLUMBING
J 0
(1215 2585);
DISPLAY 0.808511 (1215 2585);
PAINT GREEN (1215 2585);
DISPLAY INVISIBLE (1215 2585);
FORCEADD CAPACITOR..2
(1250 3050);
FORCEPROP 0 LAST PACKAGE 0402
J 0
(1350 3050);
DISPLAY 1.021277 (1350 3050);
FORCEPROP 1 LAST VALUE 0.1UF
J 0
(1350 2950);
DISPLAY 1.212766 (1350 2950);
PAINT GREEN (1350 2950);
FORCEPROP 0 LAST VOLTAGE 25V
J 0
(1350 3150);
DISPLAY 1.021277 (1350 3150);
FORCEPROP 2 LAST CDS_LIB passive
J 0
(1250 3050);
DISPLAY INVISIBLE (1250 3050);
FORCEPROP 1 LAST PATH I20
J 0
(1150 3100);
DISPLAY 1.212766 (1150 3100);
PAINT GREEN (1150 3100);
DISPLAY INVISIBLE (1150 3100);
FORCEPROP 1 LAST CDS_LMAN_SYM_OUTLINE -50,0,50,-50
J 0
(1250 3050);
DISPLAY 0.468085 (1250 3050);
PAINT GREEN (1250 3050);
DISPLAY INVISIBLE (1250 3050);
FORCEPROP 1 LAST TOLERANCE 10%
J 0
(1100 3150);
DISPLAY 1.212766 (1100 3150);
PAINT GREEN (1100 3150);
DISPLAY INVISIBLE (1100 3150);
FORCEPROP 1 LAST CLS_PN G105-0B104-EK
J 0
(1150 3100);
DISPLAY 1.212766 (1150 3100);
PAINT GREEN (1150 3100);
DISPLAY INVISIBLE (1150 3100);
FORCEPROP 1 LAST $LOCATION C304
J 0
(1300 2900);
DISPLAY 1.212766 (1300 2900);
PAINT GREEN (1300 2900);
FORCEPROP 0 LASTPIN (1250 3150) $PN 1
R 1
J 0
(1240 3160);
DISPLAY 0.680851 (1240 3160);
PAINT MONO (1240 3160);
FORCEPROP 0 LASTPIN (1250 2900) $PN 2
R 1
J 2
(1240 2890);
DISPLAY 0.680851 (1240 2890);
PAINT MONO (1240 2890);
FORCEPROP 0 LAST CDS_LOCATION C304
J 0
(1350 3200);
DISPLAY 1.021277 (1350 3200);
DISPLAY INVISIBLE (1350 3200);
FORCEPROP 0 LAST $SEC 1
J 0
(1350 3200);
DISPLAY 0.680851 (1350 3200);
PAINT MONO (1350 3200);
DISPLAY INVISIBLE (1350 3200);
FORCEPROP 0 LAST CDS_SEC 1
J 0
(1350 3200);
DISPLAY 1.021277 (1350 3200);
DISPLAY INVISIBLE (1350 3200);
FORCEADD ISL80101IRAJZ_DFN10..1
(2150 2950);
FORCEPROP 0 LAST PART_NUMBER ISL80101IRAJZ-T
J 0
(2150 3000);
DISPLAY 1.021277 (2150 3000);
FORCEPROP 1 LAST CLS_PN G222-10136-01
J 0
(2150 3100);
DISPLAY 0.978723 (2150 3100);
PAINT GREEN (2150 3100);
FORCEPROP 2 LAST CDS_LIB analog
J 0
(2150 2950);
DISPLAY INVISIBLE (2150 2950);
FORCEPROP 1 LAST PATH I29
J 0
(2200 3000);
DISPLAY 1.212766 (2200 3000);
PAINT GREEN (2200 3000);
DISPLAY INVISIBLE (2200 3000);
FORCEPROP 1 LAST CDS_LMAN_SYM_OUTLINE 0,0,900,-1000
J 0
(2150 2950);
DISPLAY 0.468085 (2150 2950);
PAINT GREEN (2150 2950);
DISPLAY INVISIBLE (2150 2950);
FORCEPROP 2 LASTPIN (3150 2550) SIG_NAME UN$525$ISL80101IRAJZDFN10$I29$SENSE
J 0
(3160 2560);
DISPLAY 0.659574 (3160 2560);
PAINT MONO (3160 2560);
DISPLAY INVISIBLE (3160 2560);
FORCEPROP 1 LAST $LOCATION U41
J 0
(2150 3200);
DISPLAY 1.212766 (2150 3200);
PAINT GREEN (2150 3200);
FORCEPROP 0 LASTPIN (2050 2350) $PN 7
J 2
(2040 2360);
DISPLAY 0.680851 (2040 2360);
PAINT MONO (2040 2360);
FORCEPROP 0 LASTPIN (3150 2150) $PN 5
J 0
(3160 2160);
DISPLAY 0.680851 (3160 2160);
PAINT MONO (3160 2160);
FORCEPROP 0 LASTPIN (2050 2550) $PN 8
J 2
(2040 2560);
DISPLAY 0.680851 (2040 2560);
PAINT MONO (2040 2560);
FORCEPROP 0 LASTPIN (3150 2350) $PN 4
J 0
(3160 2360);
DISPLAY 0.680851 (3160 2360);
PAINT MONO (3160 2360);
FORCEPROP 0 LASTPIN (3150 2550) $PN 3
J 0
(3160 2560);
DISPLAY 0.680851 (3160 2560);
PAINT MONO (3160 2560);
FORCEPROP 0 LASTPIN (2050 2150) $PN 6
J 2
(2040 2160);
DISPLAY 0.680851 (2040 2160);
PAINT MONO (2040 2160);
FORCEPROP 0 LASTPIN (3150 2050) $PN 11
J 0
(3160 2060);
DISPLAY 0.680851 (3160 2060);
PAINT MONO (3160 2060);
FORCEPROP 0 LASTPIN (2050 2850) $PN 9
J 2
(2040 2860);
DISPLAY 0.680851 (2040 2860);
PAINT MONO (2040 2860);
FORCEPROP 0 LASTPIN (2050 2750) $PN 10
J 2
(2040 2760);
DISPLAY 0.680851 (2040 2760);
PAINT MONO (2040 2760);
FORCEPROP 0 LASTPIN (3150 2850) $PN 1
J 0
(3160 2860);
DISPLAY 0.680851 (3160 2860);
PAINT MONO (3160 2860);
FORCEPROP 0 LASTPIN (3150 2750) $PN 2
J 0
(3160 2760);
DISPLAY 0.680851 (3160 2760);
PAINT MONO (3160 2760);
FORCEPROP 0 LAST CDS_LOCATION U41
J 0
(2150 3200);
DISPLAY 1.021277 (2150 3200);
DISPLAY INVISIBLE (2150 3200);
FORCEPROP 0 LAST $SEC 1
J 0
(2150 3200);
DISPLAY 0.680851 (2150 3200);
PAINT MONO (2150 3200);
DISPLAY INVISIBLE (2150 3200);
FORCEPROP 0 LAST CDS_SEC 1
J 0
(2150 3200);
DISPLAY 1.021277 (2150 3200);
DISPLAY INVISIBLE (2150 3200);
FORCEADD GND_SG..1
(3400 1350);
FORCEPROP 3 LASTPIN (3450 1400) SIG_NAME SG\g
J 0
(3460 1410);
DISPLAY 0.659574 (3460 1410);
PAINT MONO (3460 1410);
DISPLAY INVISIBLE (3460 1410);
FORCEPROP 2 LAST VOLTAGE 0
J 0
(3500 1300);
DISPLAY 1.021277 (3500 1300);
FORCEPROP 1 LAST HDL_POWER SG
J 1
(3455 1255);
DISPLAY 0.808511 (3455 1255);
PAINT GREEN (3455 1255);
FORCEPROP 1 LAST BODY_TYPE PLUMBING
J 0
(3415 1335);
DISPLAY 0.808511 (3415 1335);
PAINT GREEN (3415 1335);
DISPLAY INVISIBLE (3415 1335);
FORCEPROP 1 LAST CDS_LMAN_SYM_OUTLINE 0,0,100,-50
J 0
(3400 1350);
DISPLAY 0.468085 (3400 1350);
PAINT GREEN (3400 1350);
DISPLAY INVISIBLE (3400 1350);
FORCEPROP 1 LAST PATH I30
J 0
(3435 1350);
DISPLAY 0.808511 (3435 1350);
PAINT GREEN (3435 1350);
DISPLAY INVISIBLE (3435 1350);
FORCEPROP 2 LAST CDS_LIB cls
J 0
(3400 1350);
DISPLAY INVISIBLE (3400 1350);
FORCEADD GND_SG..1
(5450 1550);
FORCEPROP 3 LASTPIN (5500 1600) SIG_NAME SG\g
J 0
(5510 1610);
DISPLAY 0.659574 (5510 1610);
PAINT MONO (5510 1610);
DISPLAY INVISIBLE (5510 1610);
FORCEPROP 1 LAST HDL_POWER SG
J 1
(5500 1450);
DISPLAY 0.808511 (5500 1450);
PAINT GREEN (5500 1450);
FORCEPROP 1 LAST BODY_TYPE PLUMBING
J 0
(5465 1535);
DISPLAY 0.808511 (5465 1535);
PAINT GREEN (5465 1535);
DISPLAY INVISIBLE (5465 1535);
FORCEPROP 1 LAST CDS_LMAN_SYM_OUTLINE 0,0,100,-50
J 0
(5450 1550);
DISPLAY 0.468085 (5450 1550);
PAINT GREEN (5450 1550);
DISPLAY INVISIBLE (5450 1550);
FORCEPROP 1 LAST PATH I35
J 0
(5485 1550);
DISPLAY 0.808511 (5485 1550);
PAINT GREEN (5485 1550);
DISPLAY INVISIBLE (5485 1550);
FORCEPROP 2 LAST CDS_LIB cls
J 0
(5450 1550);
DISPLAY INVISIBLE (5450 1550);
FORCEADD GND_SG..1
(6700 2300);
FORCEPROP 3 LASTPIN (6750 2350) SIG_NAME SG\g
J 0
(6760 2360);
DISPLAY 0.659574 (6760 2360);
PAINT MONO (6760 2360);
DISPLAY INVISIBLE (6760 2360);
FORCEPROP 1 LAST HDL_POWER SG
J 1
(6750 2150);
DISPLAY 0.808511 (6750 2150);
PAINT GREEN (6750 2150);
FORCEPROP 1 LAST BODY_TYPE PLUMBING
J 0
(6715 2285);
DISPLAY 0.808511 (6715 2285);
PAINT GREEN (6715 2285);
DISPLAY INVISIBLE (6715 2285);
FORCEPROP 1 LAST CDS_LMAN_SYM_OUTLINE 0,0,100,-50
J 0
(6700 2300);
DISPLAY 0.468085 (6700 2300);
PAINT GREEN (6700 2300);
DISPLAY INVISIBLE (6700 2300);
FORCEPROP 1 LAST PATH I55
J 0
(6735 2300);
DISPLAY 0.808511 (6735 2300);
PAINT GREEN (6735 2300);
DISPLAY INVISIBLE (6735 2300);
FORCEPROP 2 LAST CDS_LIB cls
J 0
(6700 2300);
DISPLAY INVISIBLE (6700 2300);
FORCEADD CAPACITOR..2
(6750 2950);
FORCEPROP 0 LAST VOLTAGE 25V
J 0
(6850 3050);
DISPLAY 1.021277 (6850 3050);
FORCEPROP 1 LAST VALUE 0.1UF
J 0
(6850 2850);
DISPLAY 1.212766 (6850 2850);
PAINT GREEN (6850 2850);
FORCEPROP 0 LAST PACKAGE 0805
J 0
(6850 2950);
DISPLAY 1.021277 (6850 2950);
FORCEPROP 1 LAST CLS_PN G105-0B104-EK
J 0
(6650 3000);
DISPLAY 1.212766 (6650 3000);
PAINT GREEN (6650 3000);
DISPLAY INVISIBLE (6650 3000);
FORCEPROP 1 LAST TOLERANCE 10%
J 0
(6600 3050);
DISPLAY 1.212766 (6600 3050);
PAINT GREEN (6600 3050);
DISPLAY INVISIBLE (6600 3050);
FORCEPROP 1 LAST CDS_LMAN_SYM_OUTLINE -50,0,50,-50
J 0
(6750 2950);
DISPLAY 0.468085 (6750 2950);
PAINT GREEN (6750 2950);
DISPLAY INVISIBLE (6750 2950);
FORCEPROP 1 LAST PATH I56
J 0
(6650 3000);
DISPLAY 1.212766 (6650 3000);
PAINT GREEN (6650 3000);
DISPLAY INVISIBLE (6650 3000);
FORCEPROP 2 LAST CDS_LIB passive
J 0
(6750 2950);
DISPLAY INVISIBLE (6750 2950);
FORCEPROP 1 LAST $LOCATION C309
J 0
(6800 2800);
DISPLAY 1.212766 (6800 2800);
PAINT GREEN (6800 2800);
FORCEPROP 0 LASTPIN (6750 3050) $PN 1
R 1
J 0
(6740 3060);
DISPLAY 0.680851 (6740 3060);
PAINT MONO (6740 3060);
FORCEPROP 0 LASTPIN (6750 2800) $PN 2
R 1
J 2
(6740 2790);
DISPLAY 0.680851 (6740 2790);
PAINT MONO (6740 2790);
FORCEPROP 0 LAST CDS_LOCATION C309
J 0
(6850 3100);
DISPLAY 1.021277 (6850 3100);
DISPLAY INVISIBLE (6850 3100);
FORCEPROP 0 LAST $SEC 1
J 0
(6850 3100);
DISPLAY 0.680851 (6850 3100);
PAINT MONO (6850 3100);
DISPLAY INVISIBLE (6850 3100);
FORCEPROP 0 LAST CDS_SEC 1
J 0
(6850 3100);
DISPLAY 1.021277 (6850 3100);
DISPLAY INVISIBLE (6850 3100);
FORCEADD GND_SG..1
(-700 2700);
FORCEPROP 3 LASTPIN (-650 2750) SIG_NAME SG\g
J 0
(-640 2760);
DISPLAY 0.659574 (-640 2760);
PAINT MONO (-640 2760);
DISPLAY INVISIBLE (-640 2760);
FORCEPROP 1 LAST HDL_POWER SG
J 1
(-645 2605);
DISPLAY 0.808511 (-645 2605);
PAINT GREEN (-645 2605);
FORCEPROP 2 LAST CDS_LIB cls
J 0
(-700 2700);
DISPLAY INVISIBLE (-700 2700);
FORCEPROP 1 LAST PATH I6
J 0
(-665 2700);
DISPLAY 0.808511 (-665 2700);
PAINT GREEN (-665 2700);
DISPLAY INVISIBLE (-665 2700);
FORCEPROP 1 LAST CDS_LMAN_SYM_OUTLINE 0,0,100,-50
J 0
(-700 2700);
DISPLAY 0.468085 (-700 2700);
PAINT GREEN (-700 2700);
DISPLAY INVISIBLE (-700 2700);
FORCEPROP 1 LAST BODY_TYPE PLUMBING
J 0
(-685 2685);
DISPLAY 0.808511 (-685 2685);
PAINT GREEN (-685 2685);
DISPLAY INVISIBLE (-685 2685);
FORCEADD CAPACITOR..2
(6150 2950);
FORCEPROP 1 LAST VALUE 10UF
J 0
(6250 2850);
DISPLAY 1.212766 (6250 2850);
PAINT GREEN (6250 2850);
FORCEPROP 0 LAST VOLTAGE 25V
J 0
(6250 3050);
DISPLAY 1.021277 (6250 3050);
FORCEPROP 0 LAST PACKAGE 0805
J 0
(6250 2950);
DISPLAY 1.021277 (6250 2950);
FORCEPROP 1 LAST TOLERANCE 20%
J 0
(6000 3050);
DISPLAY 1.212766 (6000 3050);
PAINT GREEN (6000 3050);
DISPLAY INVISIBLE (6000 3050);
FORCEPROP 1 LAST CLS_PN G107-0F106-EM
J 0
(6050 3000);
DISPLAY 1.212766 (6050 3000);
PAINT GREEN (6050 3000);
DISPLAY INVISIBLE (6050 3000);
FORCEPROP 1 LAST CDS_LMAN_SYM_OUTLINE -50,0,50,-50
J 0
(6150 2950);
DISPLAY 0.468085 (6150 2950);
PAINT GREEN (6150 2950);
DISPLAY INVISIBLE (6150 2950);
FORCEPROP 1 LAST PATH I64
J 0
(6050 3000);
DISPLAY 1.212766 (6050 3000);
PAINT GREEN (6050 3000);
DISPLAY INVISIBLE (6050 3000);
FORCEPROP 2 LAST CDS_LIB passive
J 0
(6150 2950);
DISPLAY INVISIBLE (6150 2950);
FORCEPROP 1 LAST $LOCATION C308
J 0
(6200 2800);
DISPLAY 1.212766 (6200 2800);
PAINT GREEN (6200 2800);
FORCEPROP 0 LASTPIN (6150 3050) $PN 1
R 1
J 0
(6140 3060);
DISPLAY 0.680851 (6140 3060);
PAINT MONO (6140 3060);
FORCEPROP 0 LASTPIN (6150 2800) $PN 2
R 1
J 2
(6140 2790);
DISPLAY 0.680851 (6140 2790);
PAINT MONO (6140 2790);
FORCEPROP 0 LAST CDS_LOCATION C308
J 0
(6250 3100);
DISPLAY 1.021277 (6250 3100);
DISPLAY INVISIBLE (6250 3100);
FORCEPROP 0 LAST $SEC 1
J 0
(6250 3100);
DISPLAY 0.680851 (6250 3100);
PAINT MONO (6250 3100);
DISPLAY INVISIBLE (6250 3100);
FORCEPROP 0 LAST CDS_SEC 1
J 0
(6250 3100);
DISPLAY 1.021277 (6250 3100);
DISPLAY INVISIBLE (6250 3100);
FORCEADD RESISTOR..2
(300 2900);
FORCEPROP 0 LAST PACKAGE 0402
J 0
(400 3050);
DISPLAY 1.021277 (400 3050);
FORCEPROP 1 LAST VALUE 4.7KOHM
J 0
(350 2950);
DISPLAY 1.212766 (350 2950);
PAINT GREEN (350 2950);
FORCEPROP 1 LAST PATH I65
J 0
(103 3005);
DISPLAY 1.212766 (103 3005);
PAINT GREEN (103 3005);
DISPLAY INVISIBLE (103 3005);
FORCEPROP 2 LAST CDS_LIB passive
J 0
(300 2900);
DISPLAY INVISIBLE (300 2900);
FORCEPROP 1 LAST CDS_LMAN_SYM_OUTLINE -50,50,50,-100
J 0
(300 2900);
DISPLAY 0.468085 (300 2900);
PAINT GREEN (300 2900);
DISPLAY INVISIBLE (300 2900);
FORCEPROP 1 LAST CLS_PN G155-14701-01
J 0
(550 2950);
DISPLAY 1.212766 (550 2950);
PAINT GREEN (550 2950);
DISPLAY INVISIBLE (550 2950);
FORCEPROP 1 LAST TOLERANCE 1%
J 0
(550 2750);
DISPLAY 1.212766 (550 2750);
PAINT GREEN (550 2750);
DISPLAY INVISIBLE (550 2750);
FORCEPROP 1 LAST $LOCATION R487
J 0
(350 2750);
DISPLAY 1.212766 (350 2750);
PAINT GREEN (350 2750);
FORCEPROP 0 LASTPIN (300 3000) $PN 1
R 1
J 0
(290 3010);
DISPLAY 0.680851 (290 3010);
PAINT MONO (290 3010);
FORCEPROP 0 LASTPIN (300 2750) $PN 2
R 1
J 2
(290 2740);
DISPLAY 0.680851 (290 2740);
PAINT MONO (290 2740);
FORCEPROP 0 LAST CDS_LOCATION R487
J 0
(400 3100);
DISPLAY 1.021277 (400 3100);
DISPLAY INVISIBLE (400 3100);
FORCEPROP 0 LAST $SEC 1
J 0
(400 3100);
DISPLAY 0.680851 (400 3100);
PAINT MONO (400 3100);
DISPLAY INVISIBLE (400 3100);
FORCEPROP 0 LAST CDS_SEC 1
J 0
(400 3100);
DISPLAY 1.021277 (400 3100);
DISPLAY INVISIBLE (400 3100);
FORCEADD RESISTOR..2
(5500 2950);
FORCEPROP 1 LAST VALUE 10KOHM
J 0
(5550 3000);
DISPLAY 1.212766 (5550 3000);
PAINT GREEN (5550 3000);
FORCEPROP 0 LAST PACKAGE 0402
J 0
(5550 2750);
DISPLAY 1.021277 (5550 2750);
FORCEPROP 2 LAST CDS_LIB passive
J 0
(5500 2950);
DISPLAY INVISIBLE (5500 2950);
FORCEPROP 1 LAST PATH I66
J 0
(5303 3055);
DISPLAY 1.212766 (5303 3055);
PAINT GREEN (5303 3055);
DISPLAY INVISIBLE (5303 3055);
FORCEPROP 1 LAST CDS_LMAN_SYM_OUTLINE -50,50,50,-100
J 0
(5500 2950);
DISPLAY 0.468085 (5500 2950);
PAINT GREEN (5500 2950);
DISPLAY INVISIBLE (5500 2950);
FORCEPROP 1 LAST CLS_PN G155-11002-01
J 0
(5364 3150);
DISPLAY 1.212766 (5364 3150);
PAINT GREEN (5364 3150);
DISPLAY INVISIBLE (5364 3150);
FORCEPROP 1 LAST TOLERANCE 1%
J 0
(5303 3205);
DISPLAY 1.212766 (5303 3205);
PAINT GREEN (5303 3205);
DISPLAY INVISIBLE (5303 3205);
FORCEPROP 1 LAST $LOCATION R490
J 0
(5550 2800);
DISPLAY 1.212766 (5550 2800);
PAINT GREEN (5550 2800);
FORCEPROP 0 LASTPIN (5500 3050) $PN 1
R 1
J 0
(5490 3060);
DISPLAY 0.680851 (5490 3060);
PAINT MONO (5490 3060);
FORCEPROP 0 LASTPIN (5500 2800) $PN 2
R 1
J 2
(5490 2790);
DISPLAY 0.680851 (5490 2790);
PAINT MONO (5490 2790);
FORCEPROP 0 LAST CDS_LOCATION R490
J 0
(5550 3100);
DISPLAY 1.021277 (5550 3100);
DISPLAY INVISIBLE (5550 3100);
FORCEPROP 0 LAST $SEC 1
J 0
(5550 3100);
DISPLAY 0.680851 (5550 3100);
PAINT MONO (5550 3100);
DISPLAY INVISIBLE (5550 3100);
FORCEPROP 0 LAST CDS_SEC 1
J 0
(5550 3100);
DISPLAY 1.021277 (5550 3100);
DISPLAY INVISIBLE (5550 3100);
FORCEADD RESISTOR..2
(5500 2250);
FORCEPROP 1 LAST VALUE 3.24KOHM
J 0
(5550 2300);
DISPLAY 1.212766 (5550 2300);
PAINT GREEN (5550 2300);
FORCEPROP 0 LAST PACKAGE 0402
J 0
(5550 2450);
DISPLAY 1.021277 (5550 2450);
FORCEPROP 2 LAST CDS_LIB passive
J 0
(5500 2250);
DISPLAY INVISIBLE (5500 2250);
FORCEPROP 1 LAST PATH I67
J 0
(5303 2355);
DISPLAY 1.212766 (5303 2355);
PAINT GREEN (5303 2355);
DISPLAY INVISIBLE (5303 2355);
FORCEPROP 1 LAST CDS_LMAN_SYM_OUTLINE -50,50,50,-100
J 0
(5500 2250);
DISPLAY 0.468085 (5500 2250);
PAINT GREEN (5500 2250);
DISPLAY INVISIBLE (5500 2250);
FORCEPROP 1 LAST TOLERANCE 1%
J 0
(5303 2505);
DISPLAY 1.212766 (5303 2505);
PAINT GREEN (5303 2505);
DISPLAY INVISIBLE (5303 2505);
FORCEPROP 1 LAST CLS_PN G155-03241-01
J 0
(5364 2450);
DISPLAY 1.212766 (5364 2450);
PAINT GREEN (5364 2450);
DISPLAY INVISIBLE (5364 2450);
FORCEPROP 1 LAST $LOCATION R491
J 0
(5550 2100);
DISPLAY 1.212766 (5550 2100);
PAINT GREEN (5550 2100);
FORCEPROP 0 LASTPIN (5500 2350) $PN 1
R 1
J 0
(5490 2360);
DISPLAY 0.680851 (5490 2360);
PAINT MONO (5490 2360);
FORCEPROP 0 LASTPIN (5500 2100) $PN 2
R 1
J 2
(5490 2090);
DISPLAY 0.680851 (5490 2090);
PAINT MONO (5490 2090);
FORCEPROP 0 LAST CDS_LOCATION R491
J 0
(5550 2500);
DISPLAY 1.021277 (5550 2500);
DISPLAY INVISIBLE (5550 2500);
FORCEPROP 0 LAST $SEC 1
J 0
(5550 2500);
DISPLAY 0.680851 (5550 2500);
PAINT MONO (5550 2500);
DISPLAY INVISIBLE (5550 2500);
FORCEPROP 0 LAST CDS_SEC 1
J 0
(5550 2500);
DISPLAY 1.021277 (5550 2500);
DISPLAY INVISIBLE (5550 2500);
FORCEADD RESISTOR..2
(4900 2250);
FORCEPROP 0 LAST PACKAGE 0402
J 0
(4950 2450);
DISPLAY 1.021277 (4950 2450);
FORCEPROP 1 LAST VALUE 3.92KOHM
J 0
(4950 2300);
DISPLAY 1.212766 (4950 2300);
PAINT GREEN (4950 2300);
FORCEPROP 2 LAST CDS_LIB passive
J 0
(4900 2250);
DISPLAY INVISIBLE (4900 2250);
FORCEPROP 1 LAST PATH I68
J 0
(4703 2355);
DISPLAY 1.212766 (4703 2355);
PAINT GREEN (4703 2355);
DISPLAY INVISIBLE (4703 2355);
FORCEPROP 1 LAST CDS_LMAN_SYM_OUTLINE -50,50,50,-100
J 0
(4900 2250);
DISPLAY 0.468085 (4900 2250);
PAINT GREEN (4900 2250);
DISPLAY INVISIBLE (4900 2250);
FORCEPROP 1 LAST TOLERANCE 1%
J 0
(4703 2505);
DISPLAY 1.212766 (4703 2505);
PAINT GREEN (4703 2505);
DISPLAY INVISIBLE (4703 2505);
FORCEPROP 1 LAST CLS_PN G155-03921-01
J 0
(4764 2450);
DISPLAY 1.212766 (4764 2450);
PAINT GREEN (4764 2450);
DISPLAY INVISIBLE (4764 2450);
FORCEPROP 1 LAST $LOCATION R489
J 0
(4950 2100);
DISPLAY 1.212766 (4950 2100);
PAINT GREEN (4950 2100);
FORCEPROP 0 LASTPIN (4900 2350) $PN 1
R 1
J 0
(4890 2360);
DISPLAY 0.680851 (4890 2360);
PAINT MONO (4890 2360);
FORCEPROP 0 LASTPIN (4900 2100) $PN 2
R 1
J 2
(4890 2090);
DISPLAY 0.680851 (4890 2090);
PAINT MONO (4890 2090);
FORCEPROP 0 LAST CDS_LOCATION R489
J 0
(4950 2500);
DISPLAY 1.021277 (4950 2500);
DISPLAY INVISIBLE (4950 2500);
FORCEPROP 0 LAST $SEC 1
J 0
(4950 2500);
DISPLAY 0.680851 (4950 2500);
PAINT MONO (4950 2500);
DISPLAY INVISIBLE (4950 2500);
FORCEPROP 0 LAST CDS_SEC 1
J 0
(4950 2500);
DISPLAY 1.021277 (4950 2500);
DISPLAY INVISIBLE (4950 2500);
FORCEADD VCC..1
(6700 3950);
FORCEPROP 3 LASTPIN (6750 3900) SIG_NAME XP3R3V_FT4232\g
J 0
(6760 3910);
DISPLAY 0.659574 (6760 3910);
PAINT MONO (6760 3910);
DISPLAY INVISIBLE (6760 3910);
FORCEPROP 0 LAST VOLTAGE 3.3V
J 0
(6450 4100);
DISPLAY 1.021277 (6450 4100);
DISPLAY BOTH (6450 4100);
FORCEPROP 1 LAST HDL_POWER XP3R3V_FT4232
J 1
(6755 4005);
DISPLAY 1.021277 (6755 4005);
PAINT GREEN (6755 4005);
FORCEPROP 2 LAST CDS_LIB cls
J 0
(6700 3950);
DISPLAY INVISIBLE (6700 3950);
FORCEPROP 1 LAST CDS_LMAN_SYM_OUTLINE -250,250,250,-250
J 0
(6700 3950);
DISPLAY 0.468085 (6700 3950);
PAINT GREEN (6700 3950);
DISPLAY INVISIBLE (6700 3950);
FORCEPROP 1 LAST PATH I69
J 0
(6735 4040);
DISPLAY 0.808511 (6735 4040);
PAINT GREEN (6735 4040);
DISPLAY INVISIBLE (6735 4040);
FORCEPROP 1 LAST BODY_TYPE PLUMBING
J 0
(6655 3907);
DISPLAY 0.340426 (6655 3907);
PAINT GREEN (6655 3907);
DISPLAY INVISIBLE (6655 3907);
FORCEADD CAPACITOR..2
(-1100 3050);
FORCEPROP 0 LAST VOLTAGE 10V
J 0
(-1000 3250);
DISPLAY 1.021277 (-1000 3250);
FORCEPROP 0 LAST PACKAGE 0805
J 0
(-1000 3150);
DISPLAY 1.021277 (-1000 3150);
FORCEPROP 1 LAST VALUE 22UF
J 0
(-1000 3000);
DISPLAY 1.212766 (-1000 3000);
PAINT GREEN (-1000 3000);
FORCEPROP 2 LAST CDS_LIB passive
J 0
(-1100 3050);
DISPLAY INVISIBLE (-1100 3050);
FORCEPROP 1 LAST PATH I7
J 0
(-1200 3100);
DISPLAY 1.212766 (-1200 3100);
PAINT GREEN (-1200 3100);
DISPLAY INVISIBLE (-1200 3100);
FORCEPROP 1 LAST CDS_LMAN_SYM_OUTLINE -50,0,50,-50
J 0
(-1100 3050);
DISPLAY 0.468085 (-1100 3050);
PAINT GREEN (-1100 3050);
DISPLAY INVISIBLE (-1100 3050);
FORCEPROP 1 LAST TOLERANCE 20%
J 0
(-1250 3150);
DISPLAY 1.212766 (-1250 3150);
PAINT GREEN (-1250 3150);
DISPLAY INVISIBLE (-1250 3150);
FORCEPROP 1 LAST CLS_PN G107-0F226-CM
J 0
(-1200 3100);
DISPLAY 1.212766 (-1200 3100);
PAINT GREEN (-1200 3100);
DISPLAY INVISIBLE (-1200 3100);
FORCEPROP 2 LASTPIN (-1100 3150) SIG_NAME UN$525$CAPACITOR$I7$1
J 0
(-1090 3160);
DISPLAY 0.659574 (-1090 3160);
PAINT MONO (-1090 3160);
DISPLAY INVISIBLE (-1090 3160);
FORCEPROP 1 LAST $LOCATION C284
J 0
(-1050 2900);
DISPLAY 1.212766 (-1050 2900);
PAINT GREEN (-1050 2900);
FORCEPROP 0 LASTPIN (-1100 3150) $PN 1
R 1
J 0
(-1110 3160);
DISPLAY 0.680851 (-1110 3160);
PAINT MONO (-1110 3160);
FORCEPROP 0 LASTPIN (-1100 2900) $PN 2
R 1
J 2
(-1110 2890);
DISPLAY 0.680851 (-1110 2890);
PAINT MONO (-1110 2890);
FORCEPROP 0 LAST CDS_LOCATION C284
J 0
(-1000 3300);
DISPLAY 1.021277 (-1000 3300);
DISPLAY INVISIBLE (-1000 3300);
FORCEPROP 0 LAST $SEC 1
J 0
(-1000 3300);
DISPLAY 0.680851 (-1000 3300);
PAINT MONO (-1000 3300);
DISPLAY INVISIBLE (-1000 3300);
FORCEPROP 0 LAST CDS_SEC 1
J 0
(-1000 3300);
DISPLAY 1.021277 (-1000 3300);
DISPLAY INVISIBLE (-1000 3300);
FORCEADD CAPACITOR..2
(-650 3050);
FORCEPROP 0 LAST PACKAGE 0402
J 0
(-550 3150);
FORCEPROP 0 LAST VOLTAGE 25V
J 0
(-550 3250);
FORCEPROP 1 LAST VALUE 0.1UF
J 0
(-550 3050);
DISPLAY 1.212766 (-550 3050);
PAINT GREEN (-550 3050);
FORCEPROP 2 LAST CDS_LIB passive
J 0
(-650 3050);
DISPLAY INVISIBLE (-650 3050);
FORCEPROP 1 LAST PATH I8
J 0
(-750 3100);
DISPLAY 1.212766 (-750 3100);
PAINT GREEN (-750 3100);
DISPLAY INVISIBLE (-750 3100);
FORCEPROP 1 LAST CDS_LMAN_SYM_OUTLINE -50,0,50,-50
J 0
(-650 3050);
DISPLAY 0.468085 (-650 3050);
PAINT GREEN (-650 3050);
DISPLAY INVISIBLE (-650 3050);
FORCEPROP 1 LAST TOLERANCE 10%
J 0
(-800 3150);
DISPLAY 1.212766 (-800 3150);
PAINT GREEN (-800 3150);
DISPLAY INVISIBLE (-800 3150);
FORCEPROP 1 LAST CLS_PN G105-0B104-EK
J 0
(-750 3100);
DISPLAY 1.212766 (-750 3100);
PAINT GREEN (-750 3100);
DISPLAY INVISIBLE (-750 3100);
FORCEPROP 0 LAST MATERIAL X7R
J 0
(-550 3300);
DISPLAY INVISIBLE (-550 3300);
FORCEPROP 1 LAST $LOCATION C298
J 0
(-600 2900);
DISPLAY 1.212766 (-600 2900);
PAINT GREEN (-600 2900);
FORCEPROP 0 LASTPIN (-650 3150) $PN 1
R 1
J 0
(-660 3160);
DISPLAY 0.680851 (-660 3160);
PAINT MONO (-660 3160);
FORCEPROP 0 LASTPIN (-650 2900) $PN 2
R 1
J 2
(-660 2890);
DISPLAY 0.680851 (-660 2890);
PAINT MONO (-660 2890);
FORCEPROP 0 LAST CDS_LOCATION C298
J 0
(-550 3300);
DISPLAY 1.021277 (-550 3300);
DISPLAY INVISIBLE (-550 3300);
FORCEPROP 0 LAST $SEC 1
J 0
(-550 3300);
DISPLAY 0.680851 (-550 3300);
PAINT MONO (-550 3300);
DISPLAY INVISIBLE (-550 3300);
FORCEPROP 0 LAST CDS_SEC 1
J 0
(-550 3300);
DISPLAY 1.021277 (-550 3300);
DISPLAY INVISIBLE (-550 3300);
FORCEADD OFFPAGE_OUT..1
(4050 2350);
FORCEPROP 2 LAST $XR0 24D5< 
J 0
(4105 2350);
DISPLAY 0.638298 (4105 2350);
PAINT MONO (4105 2350);
FORCEPROP 2 LAST PATH I82
J 0
(4500 2400);
DISPLAY 1.021277 (4500 2400);
DISPLAY INVISIBLE (4500 2400);
FORCEPROP 1 LAST OFFPAGE TRUE
J 0
(4060 2405);
DISPLAY 0.808511 (4060 2405);
PAINT GREEN (4060 2405);
DISPLAY INVISIBLE (4060 2405);
FORCEPROP 2 LAST CDS_LIB cls
J 0
(4050 2350);
DISPLAY INVISIBLE (4050 2350);
FORCEPROP 1 LAST CDS_LMAN_SYM_OUTLINE -50,50,50,-50
J 0
(4050 2350);
DISPLAY 0.468085 (4050 2350);
PAINT GREEN (4050 2350);
DISPLAY INVISIBLE (4050 2350);
FORCEPROP 1 LAST BODY_TYPE COMMENT
J 0
(4060 2485);
DISPLAY 0.808511 (4060 2485);
PAINT GREEN (4060 2485);
DISPLAY INVISIBLE (4060 2485);
FORCEADD VCC..1
(-2900 3650);
FORCEPROP 3 LASTPIN (-2850 3600) SIG_NAME XP5R0V_FT4232\g
J 0
(-2840 3610);
DISPLAY 0.659574 (-2840 3610);
PAINT MONO (-2840 3610);
DISPLAY INVISIBLE (-2840 3610);
FORCEPROP 1 LAST HDL_POWER XP5R0V_FT4232
J 1
(-2845 3705);
DISPLAY 1.021277 (-2845 3705);
PAINT GREEN (-2845 3705);
FORCEPROP 0 LAST VOLTAGE 5V
J 0
(-3100 3800);
DISPLAY 1.021277 (-3100 3800);
DISPLAY BOTH (-3100 3800);
FORCEPROP 1 LAST BODY_TYPE PLUMBING
J 0
(-2945 3607);
DISPLAY 0.340426 (-2945 3607);
PAINT GREEN (-2945 3607);
DISPLAY INVISIBLE (-2945 3607);
FORCEPROP 1 LAST PATH I9
J 0
(-2865 3740);
DISPLAY 0.808511 (-2865 3740);
PAINT GREEN (-2865 3740);
DISPLAY INVISIBLE (-2865 3740);
FORCEPROP 1 LAST CDS_LMAN_SYM_OUTLINE -250,250,250,-250
J 0
(-2900 3650);
DISPLAY 0.468085 (-2900 3650);
PAINT GREEN (-2900 3650);
DISPLAY INVISIBLE (-2900 3650);
FORCEPROP 2 LAST CDS_LIB cls
J 0
(-2900 3650);
DISPLAY INVISIBLE (-2900 3650);
FORCEADD SHEET_A1..1
(10300 -3950);
FORCEPROP 2 LAST CUSTOM_TXT_CDS <XR_PAGE_TITLE>
J 0
(-5270 7400);
DISPLAY 0.638298 (-5270 7400);
PAINT PINK (-5270 7400);
FORCEPROP 1 LAST CUSTOM_TXT_CDS <DOCNO>
J 0
(8250 -3565);
DISPLAY 0.978723 (8250 -3565);
FORCEPROP 1 LAST CUSTOM_TXT_CDS <CON_PAGE_NUM>
J 0
(8145 -3900);
DISPLAY 0.978723 (8145 -3900);
FORCEPROP 1 LAST CUSTOM_TXT_CDS <DATE>
J 0
(9600 -3775);
DISPLAY 0.978723 (9600 -3775);
FORCEPROP 1 LAST CUSTOM_TXT_CDS <TITLE>
J 1
(8515 -3320);
DISPLAY 0.978723 (8515 -3320);
FORCEPROP 1 LAST CUSTOM_TXT_CDS <DESIGNER>
J 0
(9600 -3350);
DISPLAY 0.978723 (9600 -3350);
FORCEPROP 1 LAST CUSTOM_TXT_CDS <CON_TOTAL_PAGES>
J 0
(8455 -3900);
DISPLAY 0.808511 (8455 -3900);
FORCEPROP 1 LAST CUSTOM_TXT_CDS <ASSY_PN>
J 0
(8250 -3775);
DISPLAY 0.978723 (8250 -3775);
FORCEPROP 1 LAST CUSTOM_TXT_CDS <DOCREV>
J 0
(9600 -3575);
DISPLAY 0.978723 (9600 -3575);
FORCEPROP 1 LAST TITLE XP3R3V_FTDI
J 0
(7750 -3000);
DISPLAY 3.042553 (7750 -3000);
PAINT GREEN (7750 -3000);
FORCEPROP 2 LAST CDS_XR_PAGE_TITLE CR-33 : @TIMECARD_LIB.TIMECARD(SCH_1):PAGE33
J 0
(-5270 7400);
DISPLAY 0.638298 (-5270 7400);
PAINT PINK (-5270 7400);
DISPLAY INVISIBLE (-5270 7400);
FORCEPROP 2 LAST CDS_LIB cls
J 0
(10300 -3950);
DISPLAY INVISIBLE (10300 -3950);
FORCEPROP 1 LAST CDS_LMAN_SYM_OUTLINE -15850,11500,200,-200
J 0
(10300 -3950);
DISPLAY 0.468085 (10300 -3950);
PAINT GREEN (10300 -3950);
DISPLAY INVISIBLE (10300 -3950);
FORCEPROP 2 LAST PAGE_BORDER TRUE
J 0
(-400 3980);
DISPLAY 0.638298 (-400 3980);
PAINT PINK (-400 3980);
DISPLAY INVISIBLE (-400 3980);
FORCEPROP 1 LAST TITLE XP1R2V_FPGA
J 0
(10300 -3950);
PAINT MONO (10300 -3950);
DISPLAY INVISIBLE (10300 -3950);
FORCEPROP 1 LAST COMMENT_BODY TRUE
J 0
(10310 -3895);
DISPLAY 0.808511 (10310 -3895);
DISPLAY INVISIBLE (10310 -3895);
WIRE 16 -1 (-2300 3600)(-2300 3350);
WIRE 16 -1 (5200 3900)(5200 3700);
WIRE 16 -1 (300 1350)(300 1600);
WIRE 16 -1 (1350 1500)(1350 1700);
WIRE 16 -1 (1250 2750)(1250 2650);
WIRE 16 -1 (800 2750)(1250 2750);
WIRE 16 -1 (1250 2900)(1250 2750);
WIRE 16 -1 (3450 1400)(3450 2050);
WIRE 16 -1 (5500 1600)(5500 1900);
WIRE 16 -1 (6750 2350)(6750 2550);
WIRE 16 -1 (-650 2750)(-650 2800);
WIRE 16 -1 (6750 3900)(6750 3700);
WIRE 16 -1 (-2850 3200)(-2850 3600);
WIRE 16 -1 (-1850 3200)(-2850 3200);
WIRE 16 -1 (5500 2800)(5500 2550);
WIRE 16 -1 (5500 2350)(5500 2550);
WIRE 16 -1 (4900 2350)(4900 2550);
WIRE 16 -1 (5500 2550)(4900 2550);
WIRE 16 -1 (3150 2550)(4900 2550);
WIRE 16 -1 (3150 2750)(3500 2750);
WIRE 16 -1 (3500 2750)(3500 2850);
WIRE 16 -1 (3150 2850)(3500 2850);
WIRE 16 -1 (3500 3350)(3500 2850);
WIRE 16 -1 (3500 3350)(5500 3350);
WIRE 16 -1 (5500 3050)(5500 3350);
WIRE 16 -1 (6150 3350)(5500 3350);
WIRE 16 -1 (6150 3050)(6150 3350);
WIRE 16 -1 (6750 3050)(6750 3350);
WIRE 16 -1 (6750 3350)(6150 3350);
WIRE 16 -1 (6000 3700)(6750 3700);
WIRE 16 -1 (6750 3700)(6750 3350);
WIRE 16 -1 (-1100 2800)(-1100 2900);
WIRE 16 -1 (-650 2900)(-650 2800);
WIRE 16 -1 (-650 2800)(-1100 2800);
WIRE 16 -1 (6750 2800)(6750 2550);
WIRE 16 -1 (6150 2550)(6750 2550);
WIRE 16 -1 (6150 2800)(6150 2550);
WIRE 16 -1 (5500 1900)(5500 2100);
WIRE 16 -1 (4900 1900)(5500 1900);
WIRE 16 -1 (4900 2100)(4900 1900);
WIRE 16 -1 (3150 2050)(3450 2050);
WIRE 16 -1 (3450 2150)(3450 2050);
WIRE 16 -1 (3150 2150)(3450 2150);
WIRE 16 -1 (800 2900)(800 2750);
WIRE 16 -1 (300 1800)(300 1600);
WIRE 16 -1 (850 1600)(300 1600);
WIRE 16 -1 (850 1800)(850 1600);
WIRE 16 -1 (5200 3700)(5600 3700);
WIRE 16 -1 (-2300 3350)(-1850 3350);
WIRE 16 -1 (-1350 3200)(-1250 3200);
WIRE 16 -1 (-1350 3350)(-1250 3350);
WIRE 16 -1 (-1250 3350)(-1250 3200);
WIRE 16 -1 (-1100 3150)(-1100 3350);
WIRE 16 -1 (-1100 3350)(-1250 3350);
WIRE 16 -1 (-1100 3350)(-650 3350);
WIRE 16 -1 (-650 3350)(-650 3150);
WIRE 16 -1 (-400 3350)(-650 3350);
WIRE 8 -1 (8100 650)(8100 500);
WIRE 8 -1 (8100 650)(6800 650);
WIRE 8 -1 (6800 650)(5950 650);
WIRE 8 -1 (6800 500)(8100 500);
WIRE 8 -1 (6800 500)(6800 650);
WIRE 8 -1 (8100 500)(8100 350);
WIRE 8 -1 (8100 200)(8100 350);
WIRE 8 -1 (6800 350)(6800 500);
WIRE 8 -1 (6800 350)(8100 350);
WIRE 8 -1 (5950 650)(5950 500);
WIRE 8 -1 (5950 500)(6800 500);
WIRE 8 -1 (5950 500)(5950 350);
WIRE 8 -1 (5950 350)(6800 350);
WIRE 8 -1 (8100 50)(8100 200);
WIRE 8 -1 (6800 200)(6800 350);
WIRE 8 -1 (6800 200)(8100 200);
WIRE 8 -1 (8100 -100)(8100 50);
WIRE 8 -1 (6800 -100)(8100 -100);
WIRE 8 -1 (6800 50)(6800 200);
WIRE 8 -1 (6800 50)(8100 50);
WIRE 8 -1 (6800 -100)(6800 50);
WIRE 8 -1 (5950 200)(5950 350);
WIRE 8 -1 (5950 200)(6800 200);
WIRE 8 -1 (5950 50)(5950 200);
WIRE 8 -1 (5950 50)(6800 50);
WIRE 8 -1 (5950 -100)(6800 -100);
WIRE 8 -1 (5950 -100)(5950 50);
WIRE 16 -1 (1350 2150)(2050 2150);
WIRE 16 -1 (1350 1950)(1350 2150);
WIRE 16 -1 (850 2050)(850 2350);
WIRE 16 -1 (2050 2350)(850 2350);
WIRE 16 -1 (300 2050)(300 2350);
WIRE 16 -1 (850 2350)(300 2350);
WIRE 16 -1 (300 2750)(300 2350);
WIRE 16 -1 (2050 2750)(1700 2750);
WIRE 16 -1 (1700 2750)(1700 2850);
WIRE 16 -1 (2050 2850)(1700 2850);
WIRE 16 -1 (1700 3350)(1700 2850);
WIRE 16 -1 (1250 3150)(1250 3350);
WIRE 16 -1 (1700 3350)(1250 3350);
WIRE 16 -1 (800 3150)(800 3350);
WIRE 16 -1 (1250 3350)(800 3350);
WIRE 16 -1 (0 3350)(300 3350);
WIRE 16 -1 (800 3350)(300 3350);
WIRE 16 -1 (300 3000)(300 3350);
WIRE 16 -1 (3150 2350)(4000 2350);
FORCEPROP 2 LAST SIG_NAME XP3R3V_FT_PG
J 0
(3340 2360);
DISPLAY 1.021277 (3340 2360);
DOT 1 (3450 2050);
DOT 1 (-1250 3350);
DOT 1 (6750 3700);
DOT 1 (6750 3350);
DOT 1 (6750 2550);
DOT 1 (5500 3350);
DOT 1 (5500 2550);
DOT 1 (4900 2550);
DOT 1 (5500 1900);
DOT 1 (3500 2850);
DOT 1 (1700 2850);
DOT 1 (1250 3350);
DOT 1 (1250 2750);
DOT 1 (850 2350);
DOT 1 (300 3350);
DOT 1 (300 2350);
DOT 1 (-650 3350);
DOT 1 (-1100 3350);
DOT 1 (300 1600);
DOT 1 (8100 500);
DOT 1 (8100 350);
DOT 1 (8100 50);
DOT 1 (8100 200);
DOT 1 (6800 650);
DOT 1 (6800 500);
DOT 1 (6800 350);
DOT 1 (6800 50);
DOT 1 (6800 200);
DOT 1 (5950 500);
DOT 1 (5950 350);
DOT 1 (5950 50);
DOT 1 (5950 200);
DOT 1 (6800 -100);
DOT 1 (6150 3350);
DOT 1 (800 3350);
DOT 1 (-650 2800);
FORCENOTE
VOUT=(RTOP/RBOTTOM+1)*VFB
(4050 2800) 0;
DISPLAY LEFT (4050 2800);
DISPLAY 1.021277 (4050 2800);
FORCENOTE
SS: 2.5MS
(1850 1800) 0;
DISPLAY LEFT (1850 1800);
DISPLAY 1.595745 (1850 1800);
FORCENOTE
RTOP
(5050 2950) 0;
DISPLAY LEFT (5050 2950);
DISPLAY 1.021277 (5050 2950);
FORCENOTE
0.25A
(6250 3400) 0;
DISPLAY LEFT (6250 3400);
DISPLAY 1.595745 (6250 3400);
FORCENOTE
1.75A
(7050 -50) 0;
DISPLAY LEFT (7050 -50);
DISPLAY 1.595745 (7050 -50);
FORCENOTE
VALUE(TYP)
(7050 550) 0;
DISPLAY LEFT (7050 550);
DISPLAY 1.595745 (7050 550);
FORCENOTE
3.3V
(7050 250) 0;
DISPLAY LEFT (7050 250);
DISPLAY 1.595745 (7050 250);
FORCENOTE
OCP
(6200 -50) 0;
DISPLAY LEFT (6200 -50);
DISPLAY 1.595745 (6200 -50);
FORCENOTE
0.25A
(7050 100) 0;
DISPLAY LEFT (7050 100);
DISPLAY 1.595745 (7050 100);
FORCENOTE
5.0V
(7050 400) 0;
DISPLAY LEFT (7050 400);
DISPLAY 1.595745 (7050 400);
FORCENOTE
VFB=0.5V
(4850 2650) 0;
DISPLAY LEFT (4850 2650);
DISPLAY 1.021277 (4850 2650);
FORCENOTE
XP3R3V_REG_FT
(1050 5750) 0;
DISPLAY LEFT (1050 5750);
DISPLAY 4.914894 (1050 5750);
FORCENOTE
XP3R3V_FT4232
(6000 700) 0;
DISPLAY LEFT (6000 700);
DISPLAY 3.148936 (6000 700);
PAINT VIOLET (6000 700);
FORCENOTE
PARAMETERS
(6000 550) 0;
DISPLAY LEFT (6000 550);
DISPLAY 1.595745 (6000 550);
FORCENOTE
VIN
(6200 400) 0;
DISPLAY LEFT (6200 400);
DISPLAY 1.595745 (6200 400);
FORCENOTE
VOUT
(6200 250) 0;
DISPLAY LEFT (6200 250);
DISPLAY 1.595745 (6200 250);
FORCENOTE
IOUT
(6200 100) 0;
DISPLAY LEFT (6200 100);
DISPLAY 1.595745 (6200 100);
QUIT
